#ISCELL
  mstr_misc dns *
  *
#ISCELL
  mstr_symbols cad_note *
  *
#ISCELL
  mstr_symbols design_note *
  *
#ISCELL
  mstr_symbols intel_corp_bpage *
  *
#CELL
  mstr_analog tmp421 *
  page167_i1
#CELL
  mstr_discrete res *
  page167_i10
#ISCELL
  mstr_symbols gnd *
  page167_i12
#ISCELL
  mstr_symbols p3v3_stby *
  page167_i14
#ISCELL
  mstr_symbols gnd *
  page167_i15
#ISCELL
  mstr_standard offpage *
  page167_i16
#ISCELL
  mstr_standard offpage *
  page167_i17
#ISCELL
  mstr_symbols gnd *
  page167_i22
#ISCELL
  mstr_symbols p3v3_stby *
  page167_i23
#CELL
  mstr_discrete cap *
  page167_i24
#CELL
  mstr_discrete res *
  page167_i25
#CELL
  mstr_discrete res *
  page167_i26
#ISCELL
  mstr_symbols p3v3_stby *
  page167_i29
#CELL
  mstr_analog tmp421 *
  page167_i30
#CELL
  mstr_discrete res *
  page167_i34
#CELL
  mstr_discrete res *
  page167_i35
#CELL
  mstr_discrete res *
  page167_i38
#CELL
  dev_discrete cap_a *
  page167_i39
#CELL
  dev_discrete cap_a *
  page167_i41
#CELL
  dev_discrete cap_a *
  page167_i42
#ISCELL
  mstr_symbols gnd *
  page167_i45
#ISCELL
  mstr_symbols gnd *
  page167_i46
#ISCELL
  mstr_symbols gnd *
  page167_i47
#CELL
  mstr_memory at24c64 *
  page167_i49
#CELL
  mstr_discrete res *
  page167_i5
#CELL
  mstr_discrete res *
  page167_i50
#ISCELL
  mstr_symbols gnd *
  page167_i52
#ISCELL
  mstr_symbols gnd *
  page167_i55
#ISCELL
  mstr_symbols p3v3_stby *
  page167_i56
#ISCELL
  mstr_symbols p3v3_stby *
  page167_i57
#CELL
  mstr_discrete res *
  page167_i58
#CELL
  mstr_discrete res *
  page167_i6
#ISCELL
  mstr_standard offpage *
  page167_i60
#ISCELL
  mstr_standard offpage *
  page167_i61
#ISCELL
  mstr_standard offpage *
  page167_i62
#ISCELL
  mstr_standard offpage *
  page167_i63
#CELL
  mstr_discrete cap *
  page167_i7
#CELL
  mstr_discrete res *
  page167_i70
#ISCELL
  mstr_symbols p3v3_stby *
  page167_i71
#ISCELL
  mstr_symbols p3v3_stby *
  page167_i72
#ISCELL
  mstr_symbols p3v3_stby *
  page167_i73
#CELL
  mstr_discrete res *
  page167_i74
#CELL
  mstr_discrete res *
  page167_i75
#CELL
  mstr_discrete res *
  page167_i76
#CELL
  mstr_discrete res *
  page167_i77
#CELL
  mstr_discrete res *
  page167_i8
#CELL
  mstr_discrete res *
  page167_i80
#ISCELL
  mstr_symbols p3v3_stby *
  page167_i81
#ISCELL
  mstr_symbols p3v3_stby *
  page167_i82
#CELL
  mstr_discrete res *
  page167_i83
#CELL
  mstr_discrete res *
  page167_i84
#CELL
  mstr_discrete res *
  page167_i85
#ISCELL
  mstr_standard offpage *
  page167_i86
#ISCELL
  mstr_standard offpage *
  page167_i87
#CELL
  w_hdl 2sb2907a-b0-00001-gp *
  page167_i93
#CELL
  w_hdl 2sb2907a-b0-00001-gp *
  page167_i94
